G04 ================== begin FILE IDENTIFICATION RECORD ==================*
G04 Layout Name:  12432-1.brd*
G04 Film Name:    P_OUTLINE*
G04 File Format:  Gerber RS274X*
G04 File Origin:  Cadence Allegro 16.2-S037*
G04 Origin Date:  Wed Oct 17 10:59:32 2012*
G04 *
G04 Layer:  BOARD GEOMETRY/PANEL_OUTLINE*
G04 *
G04 Offset:    (0.00 0.00)*
G04 Mirror:    No*
G04 Mode:      Positive*
G04 Rotation:  0*
G04 FullContactRelief:  No*
G04 UndefLineWidth:     6.00*
G04 ================== end FILE IDENTIFICATION RECORD ====================*
%FSLAX35Y35*MOIN*%
%IR0*IPPOS*OFA0.00000B0.00000*MIA0B0*SFA1.00000B1.00000*%
%ADD10C,.01*%
G75*
%LPD*%
G75*
G54D10*
G01X-78740Y15000D02*
G03X-63740Y0I15000J0D01*
G01X-78740Y15000D02*
Y319646D01*
G01X-63740Y334646D02*
G03X-78740Y319646I0J-15000D01*
G01Y908315D02*
G03X-63740Y893315I15000J0D01*
G01X-78740Y908315D02*
Y1304286D01*
G01X-63740Y1319286D02*
G03X-78740Y1304286I0J-15000D01*
G01Y1892953D02*
G03X-63740Y1877953I15000J0D01*
G01X-78740Y1892953D02*
Y1977126D01*
G01X-63740Y1992126D02*
G03X-78740Y1977126I0J-15000D01*
G01X-7874Y0D02*
X-63740D01*
G01X-7874Y334646D02*
X-63740D01*
G01X-7874Y893315D02*
X-63740D01*
G01X-7874Y1319286D02*
X-63740D01*
G01X-7874Y1877953D02*
X-63740D01*
G01X-7874Y1992126D02*
X-63740D01*
G01X-7874Y17253D02*
Y0D01*
G01X0Y17214D02*
G03X-7874I-3937J0D01*
G01Y41772D02*
Y167110D01*
G01Y41772D02*
G03X0I3937J0D01*
G01Y167110D02*
G03X-7874I-3937J0D01*
G01Y191667D02*
Y308383D01*
G01Y191667D02*
G03X0I3937J0D01*
G01Y308383D02*
G03X-7874I-3937J0D01*
G01Y331986D02*
Y334646D01*
G01Y332003D02*
G03X0I3937J0D01*
G01X-7874Y905988D02*
Y893315D01*
G01X0Y905988D02*
G03X-7874I-3937J0D01*
G01Y1106301D02*
Y933234D01*
G01D02*
G03X0I3937J0D01*
G01Y1106301D02*
G03X-7874I-3937J0D01*
G01Y1280567D02*
Y1129921D01*
G01D02*
G03X0I3937J0D01*
G01Y1280567D02*
G03X-7874I-3937J0D01*
G01Y1309889D02*
Y1319286D01*
G01Y1309889D02*
G03X0I3937J0D01*
G01X-7874Y1889223D02*
Y1877953D01*
G01X0Y1889223D02*
G03X-7874I-3937J0D01*
G01X0D02*
G03X-7874I-3937J0D01*
G01Y1912843D02*
Y1962927D01*
G01Y1912843D02*
G03X0I3937J0D01*
G01Y1962927D02*
G03X-7874I-3937J0D01*
G01X0D02*
G03X-7874I-3937J0D01*
G01Y1986547D02*
Y1992126D01*
G01Y1986547D02*
G03X0I3937J0D01*
G01X3937Y0D02*
X1029528D01*
G01X0Y3937D02*
G03X3937Y0I3937J0D01*
G01X0Y409646D02*
Y3937D01*
G01X3937Y413583D02*
X0Y409646D01*
G01X19882Y413583D02*
X3937D01*
G01Y421063D02*
X19882D01*
G01X0Y425000D02*
X3937Y421063D01*
G01X0Y819094D02*
Y425000D01*
G01X3937Y823031D02*
X0Y819094D01*
G01X19882Y823031D02*
X3937D01*
G01Y830512D02*
X19882D01*
G01X0Y834449D02*
X3937Y830512D01*
G01X0Y1393898D02*
Y834449D01*
G01X3937Y1397835D02*
X0Y1393898D01*
G01X19882Y1397835D02*
X3937D01*
G01Y1405315D02*
X19882D01*
G01X0Y1409252D02*
X3937Y1405315D01*
G01X0Y1803346D02*
Y1409252D01*
G01X3937Y1807283D02*
X0Y1803346D01*
G01X19882Y1807283D02*
X3937D01*
G01Y1814764D02*
X19882D01*
G01X0Y1818701D02*
X3937Y1814764D01*
G01X0Y1988189D02*
Y1818701D01*
G01X3937Y1992126D02*
G03X0Y1988189I0J-3937D01*
G01X1029528Y1992126D02*
X3937D01*
G01X19882Y413583D02*
G03Y421063I0J3740D01*
G01Y823031D02*
G03Y830512I0J3741D01*
G01Y1397835D02*
G03Y1405315I0J3740D01*
G01Y1807283D02*
G03Y1814764I0J3740D01*
G01X989744Y1616083D02*
X1015354D01*
G01X989744D02*
G03Y1611870I0J-2107D01*
G01X1015354D02*
X989744D01*
G01X1033465Y3937D02*
Y1424882D01*
G01X1029528Y0D02*
G03X1033465Y3937I0J3937D01*
G01X1041338Y24677D02*
G03X1033464I-3937J0D01*
G01X1041338D02*
G03X1033464I-3937J0D01*
G01Y48297D02*
G03X1041338I3937J0D01*
G01Y217343D02*
G03X1033464I-3937J0D01*
G01X1041338D02*
G03X1033464I-3937J0D01*
G01Y240964D02*
G03X1041338I3937J0D01*
G01X1033464D02*
G03X1041338I3937J0D01*
G01Y445039D02*
G03X1033464I-3937J0D01*
G01X1041338D02*
G03X1033464I-3937J0D01*
G01Y468659D02*
G03X1041338I3937J0D01*
G01X1033464D02*
G03X1041338I3937J0D01*
G01Y697473D02*
G03X1033464I-3937J0D01*
G01X1041338D02*
G03X1033464I-3937J0D01*
G01Y721093D02*
G03X1041338I3937J0D01*
G01X1033464D02*
G03X1041338I3937J0D01*
G01Y996852D02*
G03X1033464I-3937J0D01*
G01X1041338D02*
G03X1033464I-3937J0D01*
G01Y1020472D02*
G03X1041338I3937J0D01*
G01X1033464D02*
G03X1041338I3937J0D01*
G01Y1344060D02*
G03X1033464I-3937J0D01*
G01X1041338D02*
G03X1033464I-3937J0D01*
G01Y1367680D02*
G03X1041338I3937J0D01*
G01X1033464D02*
G03X1041338I3937J0D01*
G01X1033465Y1424882D02*
X1029528Y1428819D01*
G01X1019291Y1433740D02*
Y1607933D01*
G01Y1433740D02*
G03X1024213Y1428819I4921J0D01*
G01X1029528D02*
X1024213D01*
G01X1015354Y1616083D02*
X1019291Y1620020D01*
G01Y1607933D02*
X1015354Y1611870D01*
G01X1019291Y1620020D02*
Y1676496D01*
G01X1029528Y1681417D02*
X1033465Y1685354D01*
G01X1024213Y1681417D02*
G03X1019291Y1676496I-1J-4921D01*
G01X1033465Y1685354D02*
Y1988189D01*
G01X1024213Y1681417D02*
X1029528D01*
G01X1041338Y1739719D02*
G03X1033464I-3937J0D01*
G01X1041338D02*
G03X1033464I-3937J0D01*
G01Y1763339D02*
G03X1041338I3937J0D01*
G01X1033464D02*
G03X1041338I3937J0D01*
G01Y1959242D02*
G03X1033464I-3937J0D01*
G01X1041338D02*
G03X1033464I-3937J0D01*
G01X1033465Y1988189D02*
G03X1029528Y1992126I-3937J0D01*
G01X1033464Y1982862D02*
G03X1041338I3937J0D01*
G01Y24677D02*
Y0D01*
G01D02*
X1097205D01*
G01X1041338Y217343D02*
Y48297D01*
G01Y445039D02*
Y240964D01*
G01Y697473D02*
Y468601D01*
G01Y996852D02*
Y721093D01*
G01Y1344060D02*
Y1020472D01*
G01Y1367680D02*
Y1393701D01*
G01D02*
X1097205D01*
G01X1041338Y1733129D02*
Y1716536D01*
G01X1065043D02*
X1041338D01*
G01Y1739719D02*
Y1731536D01*
G01Y1959242D02*
Y1763310D01*
G01Y1992126D02*
X1097205D01*
G01X1041338Y1982862D02*
Y1992126D01*
G01X1056338Y1716536D02*
X1097205D01*
G01Y0D02*
G03X1112205Y15000I0J15000D01*
G01Y1378701D02*
G03X1097205Y1393701I-15000J0D01*
G01Y1716536D02*
G03X1112205Y1731536I0J15000D01*
G01Y1977126D02*
G03X1097205Y1992126I-15000J0D01*
G01X1112205Y648419D02*
Y15000D01*
G01Y656293D02*
G03Y648419I0J-3937D01*
G01Y1378701D02*
Y656293D01*
G01Y1977126D02*
Y1731536D01*
M02*
